# S9S_MB_2U (Grand Teton) — schematic netlist excerpt (pin names and nets, part order shuffled) for the footprints in the layout excerpt that follows; sources: Cadence DE-HDL packaged netlist, KiCad conversion of 03242023_DA0F0TMBIJ0_F0T_Motherboard_J_brd_V01_OCP.brd

R2966  Q_RES  1M 1% CHIP  pkg 0402LF  page 182 : A = P3V3_RTC_AUX ; B = FM_INTRUDER_HDR_PCH_N
R4601  Q_RES  0 5% CHIP  pkg 0402LF  page 155 : A = CLK_50M_NCSI_OCP_SFF_ISO ; B = CLK_50M_NCSI_OCP_SFF_ISO_R

(kicad_pcb
	(version 20260206)
	(generator "pcbnew")
	(generator_version "10.0")
	(general
		(thickness 1.6)
		(legacy_teardrops no)
	)
	(paper "A4")
	(title_block
		(title "03242023_DA0F0TMBIJ0_F0T_Motherboard_J_brd_V01_OCP.brd")
		(comment 1 "Grand Teton / footprints 1555-1556 of 6105")
	)
	(layers
		(0 "F.Cu" signal "TOP")
		(4 "In1.Cu" signal "GND")
		(6 "In2.Cu" signal "IN1")
		(8 "In3.Cu" signal "GND1")
		(10 "In4.Cu" signal "IN2")
		(12 "In5.Cu" signal "GND2")
		(14 "In6.Cu" signal "IN3")
		(16 "In7.Cu" signal "GND3")
		(18 "In8.Cu" signal "VCC")
		(20 "In9.Cu" signal "VCC1")
		(22 "In10.Cu" signal "GND4")
		(24 "In11.Cu" signal "IN4")
		(26 "In12.Cu" signal "GND5")
		(28 "In13.Cu" signal "IN5")
		(30 "In14.Cu" signal "GND6")
		(32 "In15.Cu" signal "IN6")
		(34 "In16.Cu" signal "GND7")
		(2 "B.Cu" signal "BOTTOM")
		(9 "F.Adhes" user "F.Adhesive")
		(11 "B.Adhes" user "B.Adhesive")
		(13 "F.Paste" user "Package Geometry/Pastemask Top")
		(15 "B.Paste" user "Package Geometry/Pastemask Bottom")
		(5 "F.SilkS" user "Ref Des/Silkscreen Top")
		(7 "B.SilkS" user "Ref Des/Silkscreen Bottom")
		(1 "F.Mask" user "Board Geometry/Soldermask Top")
		(3 "B.Mask" user "Board Geometry/Soldermask Bottom")
		(17 "Dwgs.User" user "User.Drawings")
		(19 "Cmts.User" user "User.Comments")
		(21 "Eco1.User" user "User.Eco1")
		(23 "Eco2.User" user "User.Eco2")
		(25 "Edge.Cuts" user "Board Geometry/Outline")
		(27 "Margin" user)
		(31 "F.CrtYd" user "Package Geometry/Place Bound Top")
		(29 "B.CrtYd" user "Package Geometry/Place Bound Bottom")
		(35 "F.Fab" user "Ref Des/Assembly Top")
		(33 "B.Fab" user "Ref Des/Assembly Bottom")
	)
	(footprint ""
		(layer "F.Cu")
		(at 374.032018 -16.34617 180)
		(property "Reference" "R4601"
			(at 0 0 180)
			(layer "F.SilkS")
			(hide yes)
			(effects
				(font
					(size 1.27 1.27)
				)
			)
		)
		(property "Value" ""
			(at 0 0 180)
			(layer "F.Fab")
			(effects
				(font
					(size 1.27 1.27)
				)
			)
		)
		(duplicate_pad_numbers_are_jumpers no)
		(fp_line
			(start 0.7874 0.4064)
			(end -0.7874 0.4064)
			(stroke
				(width 0.1524)
				(type default)
			)
			(layer "F.SilkS")
		)
		(fp_line
			(start 0.7874 -0.4064)
			(end 0.7874 0.4064)
			(stroke
				(width 0.1524)
				(type default)
			)
			(layer "F.SilkS")
		)
		(fp_line
			(start -0.7874 0.4064)
			(end -0.7874 -0.4064)
			(stroke
				(width 0.1524)
				(type default)
			)
			(layer "F.SilkS")
		)
		(fp_line
			(start -0.7874 -0.4064)
			(end 0.7874 -0.4064)
			(stroke
				(width 0.1524)
				(type default)
			)
			(layer "F.SilkS")
		)
		(fp_line
			(start 0.67945 0.3048)
			(end 0.120396 0.3048)
			(stroke
				(width 0.1)
				(type default)
			)
			(layer "F.Fab")
		)
		(fp_line
			(start 0.67945 -0.3048)
			(end 0.67945 0.3048)
			(stroke
				(width 0.1)
				(type default)
			)
			(layer "F.Fab")
		)
		(fp_line
			(start 0.12065 -0.2794)
			(end 0.12065 -0.3048)
			(stroke
				(width 0.1)
				(type default)
			)
			(layer "F.Fab")
		)
		(fp_line
			(start 0.12065 -0.3048)
			(end 0.67945 -0.3048)
			(stroke
				(width 0.1)
				(type default)
			)
			(layer "F.Fab")
		)
		(fp_line
			(start 0.120396 0.3048)
			(end 0.120396 0.2794)
			(stroke
				(width 0.1)
				(type default)
			)
			(layer "F.Fab")
		)
		(fp_line
			(start 0.120396 0.2794)
			(end -0.12065 0.2794)
			(stroke
				(width 0.1)
				(type default)
			)
			(layer "F.Fab")
		)
		(fp_line
			(start -0.12065 0.3048)
			(end -0.67945 0.3048)
			(stroke
				(width 0.1)
				(type default)
			)
			(layer "F.Fab")
		)
		(fp_line
			(start -0.12065 0.2794)
			(end -0.12065 0.3048)
			(stroke
				(width 0.1)
				(type default)
			)
			(layer "F.Fab")
		)
		(fp_line
			(start -0.12065 -0.2794)
			(end 0.12065 -0.2794)
			(stroke
				(width 0.1)
				(type default)
			)
			(layer "F.Fab")
		)
		(fp_line
			(start -0.12065 -0.305054)
			(end -0.12065 -0.2794)
			(stroke
				(width 0.1)
				(type default)
			)
			(layer "F.Fab")
		)
		(fp_line
			(start -0.67945 0.3048)
			(end -0.67945 -0.305054)
			(stroke
				(width 0.1)
				(type default)
			)
			(layer "F.Fab")
		)
		(fp_line
			(start -0.67945 -0.305054)
			(end -0.12065 -0.305054)
			(stroke
				(width 0.1)
				(type default)
			)
			(layer "F.Fab")
		)
		(pad "1" smd circle
			(at -0.40005 0 180)
			(size 0 0)
			(layers "F.Cu" "F.Mask" "F.Paste")
			(net "CLK_50M_NCSI_OCP_SFF_ISO")
		)
		(pad "2" smd circle
			(at 0.40005 0 180)
			(size 0 0)
			(layers "F.Cu" "F.Mask" "F.Paste")
			(net "CLK_50M_NCSI_OCP_SFF_ISO_R")
		)
	)
	(footprint ""
		(layer "F.Cu")
		(at 323.815456 -27.612848 90)
		(property "Reference" "R2966"
			(at 0 0 90)
			(layer "F.SilkS")
			(hide yes)
			(effects
				(font
					(size 1.27 1.27)
				)
			)
		)
		(property "Value" ""
			(at 0 0 90)
			(layer "F.Fab")
			(effects
				(font
					(size 1.27 1.27)
				)
			)
		)
		(duplicate_pad_numbers_are_jumpers no)
		(fp_line
			(start 0.7874 -0.4064)
			(end 0.7874 0.4064)
			(stroke
				(width 0.1524)
				(type default)
			)
			(layer "F.SilkS")
		)
		(fp_line
			(start -0.7874 -0.4064)
			(end 0.7874 -0.4064)
			(stroke
				(width 0.1524)
				(type default)
			)
			(layer "F.SilkS")
		)
		(fp_line
			(start 0.7874 0.4064)
			(end -0.7874 0.4064)
			(stroke
				(width 0.1524)
				(type default)
			)
			(layer "F.SilkS")
		)
		(fp_line
			(start -0.7874 0.4064)
			(end -0.7874 -0.4064)
			(stroke
				(width 0.1524)
				(type default)
			)
			(layer "F.SilkS")
		)
		(fp_line
			(start -0.12065 -0.305054)
			(end -0.12065 -0.2794)
			(stroke
				(width 0.1)
				(type default)
			)
			(layer "F.Fab")
		)
		(fp_line
			(start -0.67945 -0.305054)
			(end -0.12065 -0.305054)
			(stroke
				(width 0.1)
				(type default)
			)
			(layer "F.Fab")
		)
		(fp_line
			(start 0.67945 -0.3048)
			(end 0.67945 0.3048)
			(stroke
				(width 0.1)
				(type default)
			)
			(layer "F.Fab")
		)
		(fp_line
			(start 0.12065 -0.3048)
			(end 0.67945 -0.3048)
			(stroke
				(width 0.1)
				(type default)
			)
			(layer "F.Fab")
		)
		(fp_line
			(start 0.12065 -0.2794)
			(end 0.12065 -0.3048)
			(stroke
				(width 0.1)
				(type default)
			)
			(layer "F.Fab")
		)
		(fp_line
			(start -0.12065 -0.2794)
			(end 0.12065 -0.2794)
			(stroke
				(width 0.1)
				(type default)
			)
			(layer "F.Fab")
		)
		(fp_line
			(start 0.120396 0.2794)
			(end -0.12065 0.2794)
			(stroke
				(width 0.1)
				(type default)
			)
			(layer "F.Fab")
		)
		(fp_line
			(start -0.12065 0.2794)
			(end -0.12065 0.3048)
			(stroke
				(width 0.1)
				(type default)
			)
			(layer "F.Fab")
		)
		(fp_line
			(start 0.67945 0.3048)
			(end 0.120396 0.3048)
			(stroke
				(width 0.1)
				(type default)
			)
			(layer "F.Fab")
		)
		(fp_line
			(start 0.120396 0.3048)
			(end 0.120396 0.2794)
			(stroke
				(width 0.1)
				(type default)
			)
			(layer "F.Fab")
		)
		(fp_line
			(start -0.12065 0.3048)
			(end -0.67945 0.3048)
			(stroke
				(width 0.1)
				(type default)
			)
			(layer "F.Fab")
		)
		(fp_line
			(start -0.67945 0.3048)
			(end -0.67945 -0.305054)
			(stroke
				(width 0.1)
				(type default)
			)
			(layer "F.Fab")
		)
		(pad "1" smd circle
			(at -0.40005 0 90)
			(size 0 0)
			(layers "F.Cu" "F.Mask" "F.Paste")
			(net "P3V3_RTC_AUX")
		)
		(pad "2" smd circle
			(at 0.40005 0 90)
			(size 0 0)
			(layers "F.Cu" "F.Mask" "F.Paste")
			(net "FM_INTRUDER_HDR_PCH_N")
		)
	)
)
